FILE_TYPE = MACRO_DRAWING;
SET COLOR_WIRE YELLOW;
SET COLOR_PROP MONO;
SET COLOR_DOT WHITE;
SET COLOR_ARC YELLOW;
SET COLOR_BODY GREEN;
SET COLOR_NOTE MONO;
SET PROP_DISPLAY VALUE;
SET PAGE_NUMBER P179;
FORCEADD INTEL_CORP_BPAGE..1
(4250 200);
FORCEPROP 1 LAST CDS_CON_LAST_MODIFIED Fri Jun 16 17:49:06 2017
J 0
(2825 525);
PAINT ORANGE (2825 525);
DISPLAY INVISIBLE (2825 525);
FORCEPROP 1 LAST CUSTOM_TXT_CDS <CURRENT_DESIGN_SHEET> OF <TOTAL_DESIGN_SHEETS>
J 0
(3750 225);
PAINT ORANGE (3750 225);
FORCEPROP 1 LAST CUSTOM_TXT_CDS <CON_LAST_MODIFIED>
J 0
(250 300);
PAINT ORANGE (250 300);
FORCEPROP 2 LAST CUSTOM_TXT_CDS <XR_PAGE_TITLE>
J 0
(-3640 5450);
DISPLAY 0.638298 (-3640 5450);
PAINT PINK (-3640 5450);
DISPLAY INVISIBLE (-3640 5450);
FORCEPROP 1 LAST SCH_TITLE SPARE
J 0
(-3700 250);
DISPLAY 1.212766 (-3700 250);
PAINT YELLOW (-3700 250);
FORCEPROP 2 LAST PAGE_BORDER TRUE
J 0
(-3640 5450);
DISPLAY 0.638298 (-3640 5450);
PAINT PINK (-3640 5450);
DISPLAY INVISIBLE (-3640 5450);
FORCEPROP 2 LAST CDS_LIB mstr_symbols
J 0
(4250 200);
PAINT MONO (4250 200);
DISPLAY INVISIBLE (4250 200);
FORCEPROP 1 LAST COMMENT_BODY TRUE
J 0
(4262 212);
DISPLAY 0.468085 (4262 212);
PAINT PEACH (4262 212);
DISPLAY INVISIBLE (4262 212);
FORCEPROP 2 LAST CDS_XR_PAGE_TITLE CR-179 : @BASEBOARD_FAB2_LIB.BASEBOARD_FAB2(SCH_1):PAGE179
J 0
(-3640 5450);
DISPLAY 0.638298 (-3640 5450);
PAINT PINK (-3640 5450);
DISPLAY INVISIBLE (-3640 5450);
QUIT
